# BASEBOARD_FAB2 (Tioga Pass) — schematic netlist excerpt (pin names and nets, part order shuffled) for the footprints in the layout excerpt that follows; sources: Cadence DE-HDL packaged netlist, KiCad conversion of Wiwynn_Tioga_Pass_MB.brd

R2R12  RES  0.0 5% CHIP  pkg 0402  page 154 : A = SPI_PCH_IO2 ; B = SPI_PCH_IO2_R1

U6M1  74CBTLV1G125  IC  pkg SMLF  page 113
  OE_N  = FM_CPU1_PKGID1
  A  = P1V8_MCP_CPU1
  B  = JTAG_MCP_CPU1_TDI_R

C2L23  CAP_A  0.01UF 25V 10% X7R  pkg 0402V  page 173 : A = SATA6G_P3_TX_C_DP ; B = SATA6G_PCH_PCIE_UP_SATA_TXP<3>

(kicad_pcb
	(version 20260206)
	(generator "pcbnew")
	(generator_version "10.0")
	(general
		(thickness 1.6)
		(legacy_teardrops no)
	)
	(paper "A4")
	(title_block
		(title "Wiwynn_Tioga_Pass_MB.brd")
		(comment 1 "Tioga Pass / footprints 4252-4254 of 4770")
	)
	(layers
		(0 "F.Cu" signal "TOP")
		(4 "In1.Cu" signal "L2GND")
		(6 "In2.Cu" signal "L3")
		(8 "In3.Cu" signal "L4GND")
		(10 "In4.Cu" signal "L5")
		(12 "In5.Cu" signal "L6GND")
		(14 "In6.Cu" signal "L7VCC")
		(16 "In7.Cu" signal "L8VCC")
		(18 "In8.Cu" signal "L9GND")
		(20 "In9.Cu" signal "L10")
		(22 "In10.Cu" signal "L11GND")
		(24 "In11.Cu" signal "L12")
		(26 "In12.Cu" signal "L13GND")
		(2 "B.Cu" signal "BOTTOM")
		(9 "F.Adhes" user "F.Adhesive")
		(11 "B.Adhes" user "B.Adhesive")
		(13 "F.Paste" user "Package Geometry/Pastemask Top")
		(15 "B.Paste" user "Package Geometry/Pastemask Bottom")
		(5 "F.SilkS" user "Ref Des/Silkscreen Top")
		(7 "B.SilkS" user "Ref Des/Silkscreen Bottom")
		(1 "F.Mask" user "Board Geometry/Soldermask Top")
		(3 "B.Mask" user "Board Geometry/Soldermask Bottom")
		(17 "Dwgs.User" user "User.Drawings")
		(19 "Cmts.User" user "User.Comments")
		(21 "Eco1.User" user "User.Eco1")
		(23 "Eco2.User" user "User.Eco2")
		(25 "Edge.Cuts" user "Board Geometry/Outline")
		(27 "Margin" user)
		(31 "F.CrtYd" user "Package Geometry/Place Bound Top")
		(29 "B.CrtYd" user "Package Geometry/Place Bound Bottom")
		(35 "F.Fab" user "Ref Des/Assembly Top")
		(33 "B.Fab" user "Ref Des/Assembly Bottom")
	)
	(footprint ""
		(layer "B.Cu")
		(at 421.513 -146.939 -90)
		(property "Reference" "C2L23"
			(at 0 0 90)
			(layer "B.SilkS")
			(hide yes)
			(effects
				(font
					(size 1.27 1.27)
				)
				(justify mirror)
			)
		)
		(property "Value" ""
			(at 0 0 90)
			(layer "B.Fab")
			(effects
				(font
					(size 1.27 1.27)
				)
				(justify mirror)
			)
		)
		(duplicate_pad_numbers_are_jumpers no)
		(fp_poly
			(pts
				(xy -0.3048 -0.1016) (xy -0.3048 0.9906) (xy 0.3048 0.9906) (xy 0.3048 -0.1016)
			)
			(stroke
				(width 0)
				(type default)
			)
			(fill no)
			(layer "B.CrtYd")
		)
		(fp_line
			(start -0.3048 0.9906)
			(end -0.3048 -0.1016)
			(stroke
				(width 0.1)
				(type default)
			)
			(layer "B.Fab")
		)
		(fp_line
			(start 0.3048 0.9906)
			(end -0.3048 0.9906)
			(stroke
				(width 0.1)
				(type default)
			)
			(layer "B.Fab")
		)
		(fp_line
			(start -0.3048 -0.1016)
			(end 0.3048 -0.1016)
			(stroke
				(width 0.1)
				(type default)
			)
			(layer "B.Fab")
		)
		(fp_line
			(start 0.3048 -0.1016)
			(end 0.3048 0.9906)
			(stroke
				(width 0.1)
				(type default)
			)
			(layer "B.Fab")
		)
		(pad "1" smd rect
			(at 0 0 90)
			(size 0.508 0.508)
			(layers "B.Cu" "B.Mask" "B.Paste")
			(net "SATA6G_P3_TX_C_DP")
		)
		(pad "2" smd rect
			(at 0 0.889 90)
			(size 0.508 0.508)
			(layers "B.Cu" "B.Mask" "B.Paste")
			(net "SATA6G_PCH_PCIE_UP_SATA_TXP<3>")
		)
		(zone
			(layer "B.Cu")
			(hatch none 0.5)
			(connect_pads
				(clearance 0)
			)
			(min_thickness 0.25)
			(keepout
				(tracks not_allowed)
				(vias allowed)
				(pads allowed)
				(copperpour not_allowed)
				(footprints allowed)
			)
			(placement
				(enabled no)
				(sheetname "")
			)
			(fill
				(thermal_gap 0.5)
				(thermal_bridge_width 0.5)
				(island_removal_mode 0)
			)
			(polygon
				(pts
					(xy 420.878 -146.685) (xy 420.878 -147.193) (xy 421.259 -147.193) (xy 421.259 -146.685)
				)
			)
		)
		(zone
			(layer "B.Cu")
			(hatch none 0.5)
			(connect_pads
				(clearance 0)
			)
			(min_thickness 0.25)
			(keepout
				(tracks allowed)
				(vias not_allowed)
				(pads allowed)
				(copperpour not_allowed)
				(footprints allowed)
			)
			(placement
				(enabled no)
				(sheetname "")
			)
			(fill
				(thermal_gap 0.5)
				(thermal_bridge_width 0.5)
				(island_removal_mode 0)
			)
			(polygon
				(pts
					(xy 421.259 -146.685) (xy 421.259 -147.193) (xy 420.878 -147.193) (xy 420.878 -146.685)
				)
			)
		)
	)
	(footprint ""
		(layer "B.Cu")
		(at 168.402 -128.905 90)
		(property "Reference" "U6M1"
			(at 0.14986 2.838958 90)
			(unlocked yes)
			(layer "B.SilkS")
			(effects
				(font
					(size 0.7874 0.5842)
					(thickness 0.1524)
				)
				(justify left mirror)
			)
		)
		(property "Value" ""
			(at 0 0 90)
			(layer "B.Fab")
			(effects
				(font
					(size 1.27 1.27)
				)
				(justify mirror)
			)
		)
		(duplicate_pad_numbers_are_jumpers no)
		(fp_circle
			(center 0.931418 -0.008382)
			(end 0.931418 0.118618)
			(stroke
				(width 0.254)
				(type default)
			)
			(fill no)
			(layer "B.SilkS")
		)
		(fp_poly
			(pts
				(xy -0.21463 -0.450088) (xy -1.56337 -0.450088) (xy -1.56337 1.75006) (xy -0.21463 1.75006)
			)
			(stroke
				(width 0)
				(type default)
			)
			(fill no)
			(layer "B.CrtYd")
		)
		(fp_line
			(start -0.21463 -0.450088)
			(end -1.56337 -0.450088)
			(stroke
				(width 0.1)
				(type default)
			)
			(layer "B.Fab")
		)
		(fp_line
			(start -1.56337 -0.450088)
			(end -1.56337 1.75006)
			(stroke
				(width 0.1)
				(type default)
			)
			(layer "B.Fab")
		)
		(fp_line
			(start -0.21463 1.75006)
			(end -0.21463 -0.450088)
			(stroke
				(width 0.1)
				(type default)
			)
			(layer "B.Fab")
		)
		(fp_line
			(start -1.56337 1.75006)
			(end -0.21463 1.75006)
			(stroke
				(width 0.1)
				(type default)
			)
			(layer "B.Fab")
		)
		(fp_circle
			(center 0.4699 -0.8382)
			(end 0.4699 -0.7112)
			(stroke
				(width 0.254)
				(type default)
			)
			(fill no)
			(layer "B.Fab")
		)
		(pad "1" smd rect
			(at 0 0 270)
			(size 1.016 0.381)
			(layers "B.Cu" "B.Mask" "B.Paste")
			(net "FM_CPU1_PKGID1")
		)
		(pad "2" smd rect
			(at 0 0.649986 270)
			(size 1.016 0.381)
			(layers "B.Cu" "B.Mask" "B.Paste")
			(net "P1V8_MCP_CPU1")
		)
		(pad "3" smd rect
			(at 0 1.299972 270)
			(size 1.016 0.381)
			(layers "B.Cu" "B.Mask" "B.Paste")
			(net "GND")
		)
		(pad "4" smd rect
			(at -1.778 1.299972 270)
			(size 1.016 0.381)
			(layers "B.Cu" "B.Mask" "B.Paste")
			(net "JTAG_MCP_CPU1_TDI_R")
		)
		(pad "5" smd rect
			(at -1.778 0 270)
			(size 1.016 0.381)
			(layers "B.Cu" "B.Mask" "B.Paste")
			(net "P3V3_STBY")
		)
	)
	(footprint ""
		(layer "B.Cu")
		(at 385.7625 -60.198 -90)
		(property "Reference" "R2R12"
			(at 0 0 90)
			(layer "B.SilkS")
			(hide yes)
			(effects
				(font
					(size 1.27 1.27)
				)
				(justify mirror)
			)
		)
		(property "Value" ""
			(at 0 0 90)
			(layer "B.Fab")
			(effects
				(font
					(size 1.27 1.27)
				)
				(justify mirror)
			)
		)
		(duplicate_pad_numbers_are_jumpers no)
		(fp_poly
			(pts
				(xy 0.2794 -0.1016) (xy -0.2794 -0.1016) (xy -0.2794 0.9906) (xy 0.2794 0.9906)
			)
			(stroke
				(width 0)
				(type default)
			)
			(fill no)
			(layer "B.CrtYd")
		)
		(fp_line
			(start -0.2794 0.9906)
			(end -0.2794 -0.1016)
			(stroke
				(width 0.1)
				(type default)
			)
			(layer "B.Fab")
		)
		(fp_line
			(start 0.2794 0.9906)
			(end -0.2794 0.9906)
			(stroke
				(width 0.1)
				(type default)
			)
			(layer "B.Fab")
		)
		(fp_line
			(start -0.2794 -0.1016)
			(end 0.2794 -0.1016)
			(stroke
				(width 0.1)
				(type default)
			)
			(layer "B.Fab")
		)
		(fp_line
			(start 0.2794 -0.1016)
			(end 0.2794 0.9906)
			(stroke
				(width 0.1)
				(type default)
			)
			(layer "B.Fab")
		)
		(pad "1" smd rect
			(at 0 0 90)
			(size 0.508 0.508)
			(layers "B.Cu" "B.Mask" "B.Paste")
			(net "SPI_PCH_IO2")
		)
		(pad "2" smd rect
			(at 0 0.889 90)
			(size 0.508 0.508)
			(layers "B.Cu" "B.Mask" "B.Paste")
			(net "SPI_PCH_IO2_R1")
		)
		(zone
			(layer "B.Cu")
			(hatch none 0.5)
			(connect_pads
				(clearance 0)
			)
			(min_thickness 0.25)
			(keepout
				(tracks not_allowed)
				(vias allowed)
				(pads allowed)
				(copperpour not_allowed)
				(footprints allowed)
			)
			(placement
				(enabled no)
				(sheetname "")
			)
			(fill
				(thermal_gap 0.5)
				(thermal_bridge_width 0.5)
				(island_removal_mode 0)
			)
			(polygon
				(pts
					(xy 385.1275 -59.944) (xy 385.1275 -60.452) (xy 385.5085 -60.452) (xy 385.5085 -59.944)
				)
			)
		)
		(zone
			(layer "B.Cu")
			(hatch none 0.5)
			(connect_pads
				(clearance 0)
			)
			(min_thickness 0.25)
			(keepout
				(tracks allowed)
				(vias not_allowed)
				(pads allowed)
				(copperpour not_allowed)
				(footprints allowed)
			)
			(placement
				(enabled no)
				(sheetname "")
			)
			(fill
				(thermal_gap 0.5)
				(thermal_bridge_width 0.5)
				(island_removal_mode 0)
			)
			(polygon
				(pts
					(xy 385.5085 -59.944) (xy 385.5085 -60.452) (xy 385.1275 -60.452) (xy 385.1275 -59.944)
				)
			)
		)
	)
)
